# S9S_MB_2U (Grand Teton) — schematic netlist excerpt (pin names and nets, part order shuffled) for the footprints in the layout excerpt that follows; sources: Cadence DE-HDL packaged netlist, KiCad conversion of 03242023_DA0F0TMBIJ0_F0T_Motherboard_J_brd_V01_OCP.brd

X19  TP_TDR_4P_FTS  TP_TDR_4P_DIP EMPTY  pkg TH  page 309
  S1  = TDR_DIFF_100_TOP_DN
  P1  = T1_GND
  P2  = T1_GND
  S2  = TDR_DIFF_100_TOP_DP

PR2529  Q_RES  10 1% EMPTY  pkg 0402LF  page 304 : A = P12V_HSC_GATE_G2 ; B = P12V_HSC_GATE2

(kicad_pcb
	(version 20260206)
	(generator "pcbnew")
	(generator_version "10.0")
	(general
		(thickness 1.6)
		(legacy_teardrops no)
	)
	(paper "A4")
	(title_block
		(title "03242023_DA0F0TMBIJ0_F0T_Motherboard_J_brd_V01_OCP.brd")
		(comment 1 "Grand Teton / footprints 1321-1322 of 6105")
	)
	(layers
		(0 "F.Cu" signal "TOP")
		(4 "In1.Cu" signal "GND")
		(6 "In2.Cu" signal "IN1")
		(8 "In3.Cu" signal "GND1")
		(10 "In4.Cu" signal "IN2")
		(12 "In5.Cu" signal "GND2")
		(14 "In6.Cu" signal "IN3")
		(16 "In7.Cu" signal "GND3")
		(18 "In8.Cu" signal "VCC")
		(20 "In9.Cu" signal "VCC1")
		(22 "In10.Cu" signal "GND4")
		(24 "In11.Cu" signal "IN4")
		(26 "In12.Cu" signal "GND5")
		(28 "In13.Cu" signal "IN5")
		(30 "In14.Cu" signal "GND6")
		(32 "In15.Cu" signal "IN6")
		(34 "In16.Cu" signal "GND7")
		(2 "B.Cu" signal "BOTTOM")
		(9 "F.Adhes" user "F.Adhesive")
		(11 "B.Adhes" user "B.Adhesive")
		(13 "F.Paste" user "Package Geometry/Pastemask Top")
		(15 "B.Paste" user "Package Geometry/Pastemask Bottom")
		(5 "F.SilkS" user "Ref Des/Silkscreen Top")
		(7 "B.SilkS" user "Ref Des/Silkscreen Bottom")
		(1 "F.Mask" user "Board Geometry/Soldermask Top")
		(3 "B.Mask" user "Board Geometry/Soldermask Bottom")
		(17 "Dwgs.User" user "User.Drawings")
		(19 "Cmts.User" user "User.Comments")
		(21 "Eco1.User" user "User.Eco1")
		(23 "Eco2.User" user "User.Eco2")
		(25 "Edge.Cuts" user "Board Geometry/Outline")
		(27 "Margin" user)
		(31 "F.CrtYd" user "Package Geometry/Place Bound Top")
		(29 "B.CrtYd" user "Package Geometry/Place Bound Bottom")
		(35 "F.Fab" user "Ref Des/Assembly Top")
		(33 "B.Fab" user "Ref Des/Assembly Bottom")
	)
	(footprint ""
		(layer "F.Cu")
		(at 262.401558 -394.17117)
		(property "Reference" "PR2529"
			(at 0 0 0)
			(layer "F.SilkS")
			(hide yes)
			(effects
				(font
					(size 1.27 1.27)
				)
			)
		)
		(property "Value" ""
			(at 0 0 0)
			(layer "F.Fab")
			(effects
				(font
					(size 1.27 1.27)
				)
			)
		)
		(duplicate_pad_numbers_are_jumpers no)
		(fp_line
			(start -0.7874 -0.4064)
			(end 0.7874 -0.4064)
			(stroke
				(width 0.1524)
				(type default)
			)
			(layer "F.SilkS")
		)
		(fp_line
			(start -0.7874 0.4064)
			(end -0.7874 -0.4064)
			(stroke
				(width 0.1524)
				(type default)
			)
			(layer "F.SilkS")
		)
		(fp_line
			(start 0.7874 -0.4064)
			(end 0.7874 0.4064)
			(stroke
				(width 0.1524)
				(type default)
			)
			(layer "F.SilkS")
		)
		(fp_line
			(start 0.7874 0.4064)
			(end -0.7874 0.4064)
			(stroke
				(width 0.1524)
				(type default)
			)
			(layer "F.SilkS")
		)
		(fp_line
			(start -0.67945 -0.305054)
			(end -0.12065 -0.305054)
			(stroke
				(width 0.1)
				(type default)
			)
			(layer "F.Fab")
		)
		(fp_line
			(start -0.67945 0.3048)
			(end -0.67945 -0.305054)
			(stroke
				(width 0.1)
				(type default)
			)
			(layer "F.Fab")
		)
		(fp_line
			(start -0.12065 -0.305054)
			(end -0.12065 -0.2794)
			(stroke
				(width 0.1)
				(type default)
			)
			(layer "F.Fab")
		)
		(fp_line
			(start -0.12065 -0.2794)
			(end 0.12065 -0.2794)
			(stroke
				(width 0.1)
				(type default)
			)
			(layer "F.Fab")
		)
		(fp_line
			(start -0.12065 0.2794)
			(end -0.12065 0.3048)
			(stroke
				(width 0.1)
				(type default)
			)
			(layer "F.Fab")
		)
		(fp_line
			(start -0.12065 0.3048)
			(end -0.67945 0.3048)
			(stroke
				(width 0.1)
				(type default)
			)
			(layer "F.Fab")
		)
		(fp_line
			(start 0.120396 0.2794)
			(end -0.12065 0.2794)
			(stroke
				(width 0.1)
				(type default)
			)
			(layer "F.Fab")
		)
		(fp_line
			(start 0.120396 0.3048)
			(end 0.120396 0.2794)
			(stroke
				(width 0.1)
				(type default)
			)
			(layer "F.Fab")
		)
		(fp_line
			(start 0.12065 -0.3048)
			(end 0.67945 -0.3048)
			(stroke
				(width 0.1)
				(type default)
			)
			(layer "F.Fab")
		)
		(fp_line
			(start 0.12065 -0.2794)
			(end 0.12065 -0.3048)
			(stroke
				(width 0.1)
				(type default)
			)
			(layer "F.Fab")
		)
		(fp_line
			(start 0.67945 -0.3048)
			(end 0.67945 0.3048)
			(stroke
				(width 0.1)
				(type default)
			)
			(layer "F.Fab")
		)
		(fp_line
			(start 0.67945 0.3048)
			(end 0.120396 0.3048)
			(stroke
				(width 0.1)
				(type default)
			)
			(layer "F.Fab")
		)
		(pad "1" smd circle
			(at -0.40005 0)
			(size 0 0)
			(layers "F.Cu" "F.Mask" "F.Paste")
			(net "P12V_HSC_GATE_G2")
		)
		(pad "2" smd circle
			(at 0.40005 0)
			(size 0 0)
			(layers "F.Cu" "F.Mask" "F.Paste")
			(net "P12V_HSC_GATE2")
		)
	)
	(footprint ""
		(layer "F.Cu")
		(at 520.044426 -148.123148 90)
		(property "Reference" "X19"
			(at -3.511804 2.541524 90)
			(unlocked yes)
			(layer "F.SilkS")
			(effects
				(font
					(size 0.7874 0.5842)
					(thickness 0.1524)
				)
				(justify left)
			)
		)
		(property "Value" ""
			(at 0 0 90)
			(layer "F.Fab")
			(effects
				(font
					(size 1.27 1.27)
				)
			)
		)
		(property "Device Type" "TP_TDR_4P_FTS_MPKT4_H025P0200_I"
			(at 1.30175 1.27 180)
			(unlocked yes)
			(layer "F.Fab")
			(hide yes)
			(effects
				(font
					(size 0.635 0.4064)
					(thickness 0.1524)
				)
			)
		)
		(property "User Part Number" "TP15"
			(at 1.30175 1.27 180)
			(unlocked yes)
			(layer "Cmts.User")
			(hide yes)
			(effects
				(font
					(size 0.635 0.4064)
					(thickness 0.1524)
				)
			)
		)
		(duplicate_pad_numbers_are_jumpers no)
		(fp_line
			(start 2.54 -1.27)
			(end 0 -1.27)
			(stroke
				(width 0.1524)
				(type default)
			)
			(layer "F.SilkS")
		)
		(fp_line
			(start 0 -1.27)
			(end 0 -0.635)
			(stroke
				(width 0.1524)
				(type default)
			)
			(layer "F.SilkS")
		)
		(fp_line
			(start 2.54 -1.1303)
			(end 2.54 -1.27)
			(stroke
				(width 0.1524)
				(type default)
			)
			(layer "F.SilkS")
		)
		(fp_line
			(start 0 0.635)
			(end 0 1.905)
			(stroke
				(width 0.1524)
				(type default)
			)
			(layer "F.SilkS")
		)
		(fp_line
			(start 2.54 1.4097)
			(end 2.54 1.1303)
			(stroke
				(width 0.1524)
				(type default)
			)
			(layer "F.SilkS")
		)
		(fp_line
			(start 0 3.175)
			(end 0 3.81)
			(stroke
				(width 0.1524)
				(type default)
			)
			(layer "F.SilkS")
		)
		(fp_line
			(start 2.54 3.81)
			(end 2.54 3.6703)
			(stroke
				(width 0.1524)
				(type default)
			)
			(layer "F.SilkS")
		)
		(fp_line
			(start 0 3.81)
			(end 2.54 3.81)
			(stroke
				(width 0.1524)
				(type default)
			)
			(layer "F.SilkS")
		)
		(fp_poly
			(pts
				(xy -1.330706 0) (xy -2.854706 0.762) (xy -2.854706 -0.762)
			)
			(stroke
				(width 0)
				(type default)
			)
			(fill yes)
			(layer "F.SilkS")
		)
		(fp_line
			(start 2.54 -1.27)
			(end 0 -1.27)
			(stroke
				(width 0.1)
				(type default)
			)
			(layer "F.Fab")
		)
		(fp_line
			(start 0 -1.27)
			(end 0 3.81)
			(stroke
				(width 0.1)
				(type default)
			)
			(layer "F.Fab")
		)
		(fp_line
			(start 2.54 3.81)
			(end 2.54 -1.27)
			(stroke
				(width 0.1)
				(type default)
			)
			(layer "F.Fab")
		)
		(fp_line
			(start 0 3.81)
			(end 2.54 3.81)
			(stroke
				(width 0.1)
				(type default)
			)
			(layer "F.Fab")
		)
		(fp_poly
			(pts
				(xy -0.761746 0) (xy -2.285746 -0.762) (xy -2.285746 0.762)
			)
			(stroke
				(width 0)
				(type default)
			)
			(fill yes)
			(layer "F.Fab")
		)
		(pad "1" thru_hole circle
			(at 0 0 90)
			(size 1.0033 1.0033)
			(drill 0.249936)
			(layers "*.Cu" "*.Mask")
			(remove_unused_layers no)
			(net "TDR_DIFF_100_TOP_DN")
			(clearance 0.10795)
			(thermal_gap 0.10795)
			(padstack
				(mode front_inner_back)
				(layer "Inner"
					(shape circle)
					(size 0.8001 0.8001)
					(clearance 0.1524)
				)
				(layer "B.Cu"
					(shape circle)
					(size 1.0033 1.0033)
					(clearance 0.10795)
				)
			)
		)
		(pad "2" thru_hole circle
			(at 2.54 0 90)
			(size 1.9939 1.9939)
			(drill 0.249936)
			(layers "*.Cu" "*.Mask")
			(remove_unused_layers no)
			(net "T1_GND")
			(clearance 0.10795)
			(thermal_gap 0.10795)
			(padstack
				(mode front_inner_back)
				(layer "Inner"
					(shape circle)
					(size 0.8001 0.8001)
					(clearance 0.1524)
				)
				(layer "B.Cu"
					(shape circle)
					(size 1.9939 1.9939)
					(clearance 0.10795)
				)
			)
		)
		(pad "3" thru_hole circle
			(at 2.54 2.54 90)
			(size 1.9939 1.9939)
			(drill 0.249936)
			(layers "*.Cu" "*.Mask")
			(remove_unused_layers no)
			(net "T1_GND")
			(clearance 0.10795)
			(thermal_gap 0.10795)
			(padstack
				(mode front_inner_back)
				(layer "Inner"
					(shape circle)
					(size 0.8001 0.8001)
					(clearance 0.1524)
				)
				(layer "B.Cu"
					(shape circle)
					(size 1.9939 1.9939)
					(clearance 0.10795)
				)
			)
		)
		(pad "4" thru_hole circle
			(at 0 2.54 90)
			(size 1.0033 1.0033)
			(drill 0.249936)
			(layers "*.Cu" "*.Mask")
			(remove_unused_layers no)
			(net "TDR_DIFF_100_TOP_DP")
			(clearance 0.10795)
			(thermal_gap 0.10795)
			(padstack
				(mode front_inner_back)
				(layer "Inner"
					(shape circle)
					(size 0.8001 0.8001)
					(clearance 0.1524)
				)
				(layer "B.Cu"
					(shape circle)
					(size 1.0033 1.0033)
					(clearance 0.10795)
				)
			)
		)
	)
)
